# BASEBOARD_FAB2 (Tioga Pass) — schematic netlist excerpt (pin names and nets, part order shuffled) for the footprints in the layout excerpt that follows; sources: Cadence DE-HDL packaged netlist, KiCad conversion of Wiwynn_Tioga_Pass_MB.brd

C4E28  SC1U10V2KX-4-GP  10%  pkg SMD-BCG6  page 214 : \1\ = P5V_STBY ; \2\ = GND
R6P9  RES  42.2 1.0% EMPTY  pkg 0402  page 103 : A = CLK_100M_CPU0_PE_REFCLK_DN ; B = GND
R7D23  RES  0.0 5% CHIP  pkg 0402  page 118 : A = RST_BMC_SRST_N ; B = RST_BMC_SRST_R_N

(kicad_pcb
	(version 20260206)
	(generator "pcbnew")
	(generator_version "10.0")
	(general
		(thickness 1.6)
		(legacy_teardrops no)
	)
	(paper "A4")
	(title_block
		(title "Wiwynn_Tioga_Pass_MB.brd")
		(comment 1 "Tioga Pass / footprints 4031-4033 of 4770")
	)
	(layers
		(0 "F.Cu" signal "TOP")
		(4 "In1.Cu" signal "L2GND")
		(6 "In2.Cu" signal "L3")
		(8 "In3.Cu" signal "L4GND")
		(10 "In4.Cu" signal "L5")
		(12 "In5.Cu" signal "L6GND")
		(14 "In6.Cu" signal "L7VCC")
		(16 "In7.Cu" signal "L8VCC")
		(18 "In8.Cu" signal "L9GND")
		(20 "In9.Cu" signal "L10")
		(22 "In10.Cu" signal "L11GND")
		(24 "In11.Cu" signal "L12")
		(26 "In12.Cu" signal "L13GND")
		(2 "B.Cu" signal "BOTTOM")
		(9 "F.Adhes" user "F.Adhesive")
		(11 "B.Adhes" user "B.Adhesive")
		(13 "F.Paste" user "Package Geometry/Pastemask Top")
		(15 "B.Paste" user "Package Geometry/Pastemask Bottom")
		(5 "F.SilkS" user "Ref Des/Silkscreen Top")
		(7 "B.SilkS" user "Ref Des/Silkscreen Bottom")
		(1 "F.Mask" user "Board Geometry/Soldermask Top")
		(3 "B.Mask" user "Board Geometry/Soldermask Bottom")
		(17 "Dwgs.User" user "User.Drawings")
		(19 "Cmts.User" user "User.Comments")
		(21 "Eco1.User" user "User.Eco1")
		(23 "Eco2.User" user "User.Eco2")
		(25 "Edge.Cuts" user "Board Geometry/Outline")
		(27 "Margin" user)
		(31 "F.CrtYd" user "Package Geometry/Place Bound Top")
		(29 "B.CrtYd" user "Package Geometry/Place Bound Bottom")
		(35 "F.Fab" user "Ref Des/Assembly Top")
		(33 "B.Fab" user "Ref Des/Assembly Bottom")
	)
	(footprint ""
		(layer "B.Cu")
		(at 176.212754 -85.217 -90)
		(property "Reference" "R6P9"
			(at 0 0 90)
			(layer "B.SilkS")
			(hide yes)
			(effects
				(font
					(size 1.27 1.27)
				)
				(justify mirror)
			)
		)
		(property "Value" ""
			(at 0 0 90)
			(layer "B.Fab")
			(effects
				(font
					(size 1.27 1.27)
				)
				(justify mirror)
			)
		)
		(duplicate_pad_numbers_are_jumpers no)
		(fp_poly
			(pts
				(xy 0.2794 -0.1016) (xy -0.2794 -0.1016) (xy -0.2794 0.9906) (xy 0.2794 0.9906)
			)
			(stroke
				(width 0)
				(type default)
			)
			(fill no)
			(layer "B.CrtYd")
		)
		(fp_line
			(start -0.2794 0.9906)
			(end -0.2794 -0.1016)
			(stroke
				(width 0.1)
				(type default)
			)
			(layer "B.Fab")
		)
		(fp_line
			(start 0.2794 0.9906)
			(end -0.2794 0.9906)
			(stroke
				(width 0.1)
				(type default)
			)
			(layer "B.Fab")
		)
		(fp_line
			(start -0.2794 -0.1016)
			(end 0.2794 -0.1016)
			(stroke
				(width 0.1)
				(type default)
			)
			(layer "B.Fab")
		)
		(fp_line
			(start 0.2794 -0.1016)
			(end 0.2794 0.9906)
			(stroke
				(width 0.1)
				(type default)
			)
			(layer "B.Fab")
		)
		(pad "1" smd rect
			(at 0 0 90)
			(size 0.508 0.508)
			(layers "B.Cu" "B.Mask" "B.Paste")
			(net "CLK_100M_CPU0_PE_REFCLK_DN")
		)
		(pad "2" smd rect
			(at 0 0.889 90)
			(size 0.508 0.508)
			(layers "B.Cu" "B.Mask" "B.Paste")
			(net "GND")
		)
		(zone
			(layer "B.Cu")
			(hatch none 0.5)
			(connect_pads
				(clearance 0)
			)
			(min_thickness 0.25)
			(keepout
				(tracks not_allowed)
				(vias allowed)
				(pads allowed)
				(copperpour not_allowed)
				(footprints allowed)
			)
			(placement
				(enabled no)
				(sheetname "")
			)
			(fill
				(thermal_gap 0.5)
				(thermal_bridge_width 0.5)
				(island_removal_mode 0)
			)
			(polygon
				(pts
					(xy 175.577754 -84.963) (xy 175.577754 -85.471) (xy 175.958754 -85.471) (xy 175.958754 -84.963)
				)
			)
		)
		(zone
			(layer "B.Cu")
			(hatch none 0.5)
			(connect_pads
				(clearance 0)
			)
			(min_thickness 0.25)
			(keepout
				(tracks allowed)
				(vias not_allowed)
				(pads allowed)
				(copperpour not_allowed)
				(footprints allowed)
			)
			(placement
				(enabled no)
				(sheetname "")
			)
			(fill
				(thermal_gap 0.5)
				(thermal_bridge_width 0.5)
				(island_removal_mode 0)
			)
			(polygon
				(pts
					(xy 175.958754 -84.963) (xy 175.958754 -85.471) (xy 175.577754 -85.471) (xy 175.577754 -84.963)
				)
			)
		)
	)
	(footprint ""
		(layer "B.Cu")
		(at 372.5418 -90.805 90)
		(property "Reference" "R7D23"
			(at 0 0 90)
			(layer "B.SilkS")
			(hide yes)
			(effects
				(font
					(size 1.27 1.27)
				)
				(justify mirror)
			)
		)
		(property "Value" ""
			(at 0 0 90)
			(layer "B.Fab")
			(effects
				(font
					(size 1.27 1.27)
				)
				(justify mirror)
			)
		)
		(duplicate_pad_numbers_are_jumpers no)
		(fp_poly
			(pts
				(xy 0.2794 -0.1016) (xy -0.2794 -0.1016) (xy -0.2794 0.9906) (xy 0.2794 0.9906)
			)
			(stroke
				(width 0)
				(type default)
			)
			(fill no)
			(layer "B.CrtYd")
		)
		(fp_line
			(start 0.2794 -0.1016)
			(end 0.2794 0.9906)
			(stroke
				(width 0.1)
				(type default)
			)
			(layer "B.Fab")
		)
		(fp_line
			(start -0.2794 -0.1016)
			(end 0.2794 -0.1016)
			(stroke
				(width 0.1)
				(type default)
			)
			(layer "B.Fab")
		)
		(fp_line
			(start 0.2794 0.9906)
			(end -0.2794 0.9906)
			(stroke
				(width 0.1)
				(type default)
			)
			(layer "B.Fab")
		)
		(fp_line
			(start -0.2794 0.9906)
			(end -0.2794 -0.1016)
			(stroke
				(width 0.1)
				(type default)
			)
			(layer "B.Fab")
		)
		(pad "1" smd rect
			(at 0 0 270)
			(size 0.508 0.508)
			(layers "B.Cu" "B.Mask" "B.Paste")
			(net "RST_BMC_SRST_N")
		)
		(pad "2" smd rect
			(at 0 0.889 270)
			(size 0.508 0.508)
			(layers "B.Cu" "B.Mask" "B.Paste")
			(net "RST_BMC_SRST_R_N")
		)
		(zone
			(layer "B.Cu")
			(hatch none 0.5)
			(connect_pads
				(clearance 0)
			)
			(min_thickness 0.25)
			(keepout
				(tracks allowed)
				(vias not_allowed)
				(pads allowed)
				(copperpour not_allowed)
				(footprints allowed)
			)
			(placement
				(enabled no)
				(sheetname "")
			)
			(fill
				(thermal_gap 0.5)
				(thermal_bridge_width 0.5)
				(island_removal_mode 0)
			)
			(polygon
				(pts
					(xy 372.7958 -91.059) (xy 372.7958 -90.551) (xy 373.1768 -90.551) (xy 373.1768 -91.059)
				)
			)
		)
		(zone
			(layer "B.Cu")
			(hatch none 0.5)
			(connect_pads
				(clearance 0)
			)
			(min_thickness 0.25)
			(keepout
				(tracks not_allowed)
				(vias allowed)
				(pads allowed)
				(copperpour not_allowed)
				(footprints allowed)
			)
			(placement
				(enabled no)
				(sheetname "")
			)
			(fill
				(thermal_gap 0.5)
				(thermal_bridge_width 0.5)
				(island_removal_mode 0)
			)
			(polygon
				(pts
					(xy 373.1768 -91.059) (xy 373.1768 -90.551) (xy 372.7958 -90.551) (xy 372.7958 -91.059)
				)
			)
		)
	)
	(footprint ""
		(layer "B.Cu")
		(at 177.1015 -57.531 -90)
		(property "Reference" "C4E28"
			(at 0 0 90)
			(layer "B.SilkS")
			(hide yes)
			(effects
				(font
					(size 1.27 1.27)
				)
				(justify mirror)
			)
		)
		(property "Value" "*"
			(at -1.1811 -2.8194 270)
			(unlocked yes)
			(layer "B.Fab")
			(hide yes)
			(effects
				(font
					(size 1.27 1.016)
					(thickness 0.1524)
				)
				(justify mirror)
			)
		)
		(property "Device Type" "SC1U10V2KX-4-GP_SMD-BCG6-SC1U1A"
			(at -1.1811 -4.3434 270)
			(unlocked yes)
			(layer "B.Fab")
			(hide yes)
			(effects
				(font
					(size 1.27 1.016)
					(thickness 0.1524)
				)
				(justify mirror)
			)
		)
		(duplicate_pad_numbers_are_jumpers no)
		(fp_rect
			(start 0.4318 0.9525)
			(end -0.4318 -0.9525)
			(stroke
				(width 0)
				(type default)
			)
			(fill no)
			(layer "B.CrtYd")
		)
		(fp_rect
			(start 0.4318 0.9525)
			(end -0.4318 -0.9525)
			(stroke
				(width 0)
				(type default)
			)
			(fill no)
			(layer "B.Fab")
		)
		(pad "1" smd custom
			(at 0 -0.4445 90)
			(size 0.1524 0.1524)
			(layers "B.Cu" "B.Mask" "B.Paste")
			(net "P5V_STBY")
			(options
				(clearance outline)
				(anchor circle)
			)
			(primitives
				(gr_poly
					(pts
						(arc
							(start 0.3048 0.2032)
							(mid 0.275042 0.275042)
							(end 0.2032 0.3048)
						)
						(arc
							(start -0.2032 0.3048)
							(mid -0.275042 0.275042)
							(end -0.3048 0.2032)
						)
						(arc
							(start -0.3048 -0.2032)
							(mid -0.275042 -0.275042)
							(end -0.2032 -0.3048)
						)
						(arc
							(start 0.2032 -0.3048)
							(mid 0.275042 -0.275042)
							(end 0.3048 -0.2032)
						)
					)
					(width 0)
					(fill yes)
				)
			)
		)
		(pad "2" smd custom
			(at 0 0.4445 90)
			(size 0.1524 0.1524)
			(layers "B.Cu" "B.Mask" "B.Paste")
			(net "GND")
			(options
				(clearance outline)
				(anchor circle)
			)
			(primitives
				(gr_poly
					(pts
						(arc
							(start 0.3048 0.2032)
							(mid 0.275042 0.275042)
							(end 0.2032 0.3048)
						)
						(arc
							(start -0.2032 0.3048)
							(mid -0.275042 0.275042)
							(end -0.3048 0.2032)
						)
						(arc
							(start -0.3048 -0.2032)
							(mid -0.275042 -0.275042)
							(end -0.2032 -0.3048)
						)
						(arc
							(start 0.2032 -0.3048)
							(mid 0.275042 -0.275042)
							(end 0.3048 -0.2032)
						)
					)
					(width 0)
					(fill yes)
				)
			)
		)
	)
)
